(kicad_pcb
	(version 20260206)
	(generator "pcbnew")
	(generator_version "10.0")
	(general
		(thickness 1.6)
		(legacy_teardrops no)
	)
	(paper "A4")
	(title_block
		(title "Wiwynn_Tioga_Pass_MB.brd")
		(comment 1 "Tioga Pass / footprints 2425-2431 of 4770")
	)
	(layers
		(0 "F.Cu" signal "TOP")
		(4 "In1.Cu" signal "L2GND")
		(6 "In2.Cu" signal "L3")
		(8 "In3.Cu" signal "L4GND")
		(10 "In4.Cu" signal "L5")
		(12 "In5.Cu" signal "L6GND")
		(14 "In6.Cu" signal "L7VCC")
		(16 "In7.Cu" signal "L8VCC")
		(18 "In8.Cu" signal "L9GND")
		(20 "In9.Cu" signal "L10")
		(22 "In10.Cu" signal "L11GND")
		(24 "In11.Cu" signal "L12")
		(26 "In12.Cu" signal "L13GND")
		(2 "B.Cu" signal "BOTTOM")
		(9 "F.Adhes" user "F.Adhesive")
		(11 "B.Adhes" user "B.Adhesive")
		(13 "F.Paste" user "Package Geometry/Pastemask Top")
		(15 "B.Paste" user "Package Geometry/Pastemask Bottom")
		(5 "F.SilkS" user "Ref Des/Silkscreen Top")
		(7 "B.SilkS" user "Ref Des/Silkscreen Bottom")
		(1 "F.Mask" user "Board Geometry/Soldermask Top")
		(3 "B.Mask" user "Board Geometry/Soldermask Bottom")
		(17 "Dwgs.User" user "User.Drawings")
		(19 "Cmts.User" user "User.Comments")
		(21 "Eco1.User" user "User.Eco1")
		(23 "Eco2.User" user "User.Eco2")
		(25 "Edge.Cuts" user "Board Geometry/Outline")
		(27 "Margin" user)
		(31 "F.CrtYd" user "Package Geometry/Place Bound Top")
		(29 "B.CrtYd" user "Package Geometry/Place Bound Bottom")
		(35 "F.Fab" user "Ref Des/Assembly Top")
		(33 "B.Fab" user "Ref Des/Assembly Bottom")
	)
	(footprint ""
		(layer "B.Cu")
		(at 93.086428 -144.89684 -90)
		(property "Reference" "C8L12"
			(at 0 0 90)
			(layer "B.SilkS")
			(hide yes)
			(effects
				(font
					(size 1.27 1.27)
				)
				(justify mirror)
			)
		)
		(property "Value" ""
			(at 0 0 90)
			(layer "B.Fab")
			(effects
				(font
					(size 1.27 1.27)
				)
				(justify mirror)
			)
		)
		(duplicate_pad_numbers_are_jumpers no)
		(fp_rect
			(start 0.500126 1.598422)
			(end -0.500126 -0.201422)
			(stroke
				(width 0)
				(type default)
			)
			(fill no)
			(layer "B.CrtYd")
		)
		(fp_line
			(start -0.500126 1.598422)
			(end 0.500126 1.598422)
			(stroke
				(width 0.1)
				(type default)
			)
			(layer "B.Fab")
		)
		(fp_line
			(start 0.500126 1.598422)
			(end 0.500126 -0.201422)
			(stroke
				(width 0.1)
				(type default)
			)
			(layer "B.Fab")
		)
		(fp_line
			(start -0.500126 -0.201422)
			(end -0.500126 1.598422)
			(stroke
				(width 0.1)
				(type default)
			)
			(layer "B.Fab")
		)
		(fp_line
			(start 0.500126 -0.201422)
			(end -0.500126 -0.201422)
			(stroke
				(width 0.1)
				(type default)
			)
			(layer "B.Fab")
		)
		(pad "1" smd rect
			(at 0 0 180)
			(size 0.889 0.9906)
			(layers "B.Cu" "B.Mask" "B.Paste")
			(net "PVDDQ_KLM")
		)
		(pad "2" smd rect
			(at 0 1.397 180)
			(size 0.889 0.9906)
			(layers "B.Cu" "B.Mask" "B.Paste")
			(net "GND")
		)
		(zone
			(layer "B.Cu")
			(hatch none 0.5)
			(connect_pads
				(clearance 0)
			)
			(min_thickness 0.25)
			(keepout
				(tracks not_allowed)
				(vias allowed)
				(pads allowed)
				(copperpour not_allowed)
				(footprints allowed)
			)
			(placement
				(enabled no)
				(sheetname "")
			)
			(fill
				(thermal_gap 0.5)
				(thermal_bridge_width 0.5)
				(island_removal_mode 0)
			)
			(polygon
				(pts
					(xy 92.133928 -144.40154) (xy 92.641928 -144.40154) (xy 92.641928 -145.39214) (xy 92.133928 -145.39214)
				)
			)
		)
		(zone
			(layer "B.Cu")
			(hatch none 0.5)
			(connect_pads
				(clearance 0)
			)
			(min_thickness 0.25)
			(keepout
				(tracks allowed)
				(vias not_allowed)
				(pads allowed)
				(copperpour not_allowed)
				(footprints allowed)
			)
			(placement
				(enabled no)
				(sheetname "")
			)
			(fill
				(thermal_gap 0.5)
				(thermal_bridge_width 0.5)
				(island_removal_mode 0)
			)
			(polygon
				(pts
					(xy 92.133928 -144.40154) (xy 92.641928 -144.40154) (xy 92.641928 -145.39214) (xy 92.133928 -145.39214)
				)
			)
		)
	)
	(footprint ""
		(layer "B.Cu")
		(at 45.611796 -100.676202 -90)
		(property "Reference" "C9N11"
			(at -0.008128 -3.664204 0)
			(unlocked yes)
			(layer "B.SilkS")
			(effects
				(font
					(size 0.7874 0.5842)
					(thickness 0.1524)
				)
				(justify mirror)
			)
		)
		(property "Value" ""
			(at 0 0 90)
			(layer "B.Fab")
			(effects
				(font
					(size 1.27 1.27)
				)
				(justify mirror)
			)
		)
		(duplicate_pad_numbers_are_jumpers no)
		(fp_line
			(start -2.286 7.366)
			(end -1.600708 7.366)
			(stroke
				(width 0.1524)
				(type default)
			)
			(layer "B.SilkS")
		)
		(fp_line
			(start -2.286 7.366)
			(end -2.286 1.63195)
			(stroke
				(width 0.1524)
				(type default)
			)
			(layer "B.SilkS")
		)
		(fp_line
			(start 2.286 7.366)
			(end 1.60147 7.366)
			(stroke
				(width 0.1524)
				(type default)
			)
			(layer "B.SilkS")
		)
		(fp_line
			(start 2.286 7.366)
			(end 2.286 1.632712)
			(stroke
				(width 0.1524)
				(type default)
			)
			(layer "B.SilkS")
		)
		(fp_line
			(start -2.504948 1.633728)
			(end -1.6002 1.633728)
			(stroke
				(width 0.1524)
				(type default)
			)
			(layer "B.SilkS")
		)
		(fp_line
			(start 2.563114 1.633728)
			(end 1.6002 1.633728)
			(stroke
				(width 0.1524)
				(type default)
			)
			(layer "B.SilkS")
		)
		(fp_line
			(start -2.504948 -1.616456)
			(end -2.504948 1.633728)
			(stroke
				(width 0.1524)
				(type default)
			)
			(layer "B.SilkS")
		)
		(fp_line
			(start -1.6002 -1.616456)
			(end -2.504948 -1.616456)
			(stroke
				(width 0.1524)
				(type default)
			)
			(layer "B.SilkS")
		)
		(fp_line
			(start 1.6002 -1.616456)
			(end 2.563114 -1.616456)
			(stroke
				(width 0.1524)
				(type default)
			)
			(layer "B.SilkS")
		)
		(fp_line
			(start 2.563114 -1.616456)
			(end 2.563114 1.633728)
			(stroke
				(width 0.1524)
				(type default)
			)
			(layer "B.SilkS")
		)
		(fp_rect
			(start 2.286 7.366)
			(end -2.286 -0.254)
			(stroke
				(width 0)
				(type default)
			)
			(fill no)
			(layer "B.CrtYd")
		)
		(fp_line
			(start -2.286 7.366)
			(end 2.286 7.366)
			(stroke
				(width 0.1)
				(type default)
			)
			(layer "B.Fab")
		)
		(fp_line
			(start 2.286 7.366)
			(end 2.286 -0.254)
			(stroke
				(width 0.1)
				(type default)
			)
			(layer "B.Fab")
		)
		(fp_line
			(start -2.286 -0.254)
			(end -2.286 7.366)
			(stroke
				(width 0.1)
				(type default)
			)
			(layer "B.Fab")
		)
		(fp_line
			(start 2.286 -0.254)
			(end -2.286 -0.254)
			(stroke
				(width 0.1)
				(type default)
			)
			(layer "B.Fab")
		)
		(pad "1" smd rect
			(at 0 0 90)
			(size 2.54 3.048)
			(layers "B.Cu" "B.Mask" "B.Paste")
			(net "PVSA_CPU1")
		)
		(pad "2" smd rect
			(at 0 7.112 90)
			(size 2.54 3.048)
			(layers "B.Cu" "B.Mask" "B.Paste")
			(net "GND")
		)
	)
	(footprint ""
		(layer "B.Cu")
		(at 388.1374 -109.7534)
		(property "Reference" "C3N12"
			(at 0 0 0)
			(layer "B.SilkS")
			(hide yes)
			(effects
				(font
					(size 1.27 1.27)
				)
				(justify mirror)
			)
		)
		(property "Value" ""
			(at 0 0 0)
			(layer "B.Fab")
			(effects
				(font
					(size 1.27 1.27)
				)
				(justify mirror)
			)
		)
		(duplicate_pad_numbers_are_jumpers no)
		(fp_poly
			(pts
				(xy 0.4953 -0.2032) (xy -0.4953 -0.2032) (xy -0.4953 1.6002) (xy 0.4953 1.6002)
			)
			(stroke
				(width 0)
				(type default)
			)
			(fill no)
			(layer "B.CrtYd")
		)
		(fp_line
			(start -0.4953 -0.2032)
			(end -0.4953 1.6002)
			(stroke
				(width 0.1)
				(type default)
			)
			(layer "B.Fab")
		)
		(fp_line
			(start -0.4953 1.6002)
			(end 0.4953 1.6002)
			(stroke
				(width 0.1)
				(type default)
			)
			(layer "B.Fab")
		)
		(fp_line
			(start 0.4953 -0.2032)
			(end -0.4953 -0.2032)
			(stroke
				(width 0.1)
				(type default)
			)
			(layer "B.Fab")
		)
		(fp_line
			(start 0.4953 1.6002)
			(end 0.4953 -0.2032)
			(stroke
				(width 0.1)
				(type default)
			)
			(layer "B.Fab")
		)
		(pad "1" smd rect
			(at 0 0 180)
			(size 0.762 0.889)
			(layers "B.Cu" "B.Mask" "B.Paste")
			(net "PVNN_PCH_STBY")
		)
		(pad "2" smd rect
			(at 0 1.397 180)
			(size 0.762 0.889)
			(layers "B.Cu" "B.Mask" "B.Paste")
			(net "GND")
		)
		(zone
			(layer "B.Cu")
			(hatch none 0.5)
			(connect_pads
				(clearance 0)
			)
			(min_thickness 0.25)
			(keepout
				(tracks not_allowed)
				(vias allowed)
				(pads allowed)
				(copperpour not_allowed)
				(footprints allowed)
			)
			(placement
				(enabled no)
				(sheetname "")
			)
			(fill
				(thermal_gap 0.5)
				(thermal_bridge_width 0.5)
				(island_removal_mode 0)
			)
			(polygon
				(pts
					(xy 388.5184 -109.3089) (xy 387.7564 -109.3089) (xy 387.7564 -108.8009) (xy 388.5184 -108.8009)
				)
			)
		)
	)
	(footprint ""
		(layer "B.Cu")
		(at 336.140806 -61.257434)
		(property "Reference" "C2U5"
			(at 0 0 0)
			(layer "B.SilkS")
			(hide yes)
			(effects
				(font
					(size 1.27 1.27)
				)
				(justify mirror)
			)
		)
		(property "Value" ""
			(at 0 0 0)
			(layer "B.Fab")
			(effects
				(font
					(size 1.27 1.27)
				)
				(justify mirror)
			)
		)
		(duplicate_pad_numbers_are_jumpers no)
		(fp_poly
			(pts
				(xy -0.3048 -0.1016) (xy -0.3048 0.9906) (xy 0.3048 0.9906) (xy 0.3048 -0.1016)
			)
			(stroke
				(width 0)
				(type default)
			)
			(fill no)
			(layer "B.CrtYd")
		)
		(fp_line
			(start -0.3048 -0.1016)
			(end 0.3048 -0.1016)
			(stroke
				(width 0.1)
				(type default)
			)
			(layer "B.Fab")
		)
		(fp_line
			(start -0.3048 0.9906)
			(end -0.3048 -0.1016)
			(stroke
				(width 0.1)
				(type default)
			)
			(layer "B.Fab")
		)
		(fp_line
			(start 0.3048 -0.1016)
			(end 0.3048 0.9906)
			(stroke
				(width 0.1)
				(type default)
			)
			(layer "B.Fab")
		)
		(fp_line
			(start 0.3048 0.9906)
			(end -0.3048 0.9906)
			(stroke
				(width 0.1)
				(type default)
			)
			(layer "B.Fab")
		)
		(pad "1" smd rect
			(at 0 0 180)
			(size 0.508 0.508)
			(layers "B.Cu" "B.Mask" "B.Paste")
			(net "P3E_CPU0_PE1_PCH_RXP<1>")
		)
		(pad "2" smd rect
			(at 0 0.889 180)
			(size 0.508 0.508)
			(layers "B.Cu" "B.Mask" "B.Paste")
			(net "P3E_CPU0_PE1_SS_RXP<1>")
		)
		(zone
			(layer "B.Cu")
			(hatch none 0.5)
			(connect_pads
				(clearance 0)
			)
			(min_thickness 0.25)
			(keepout
				(tracks allowed)
				(vias not_allowed)
				(pads allowed)
				(copperpour not_allowed)
				(footprints allowed)
			)
			(placement
				(enabled no)
				(sheetname "")
			)
			(fill
				(thermal_gap 0.5)
				(thermal_bridge_width 0.5)
				(island_removal_mode 0)
			)
			(polygon
				(pts
					(xy 336.394806 -61.003434) (xy 335.886806 -61.003434) (xy 335.886806 -60.622434) (xy 336.394806 -60.622434)
				)
			)
		)
		(zone
			(layer "B.Cu")
			(hatch none 0.5)
			(connect_pads
				(clearance 0)
			)
			(min_thickness 0.25)
			(keepout
				(tracks not_allowed)
				(vias allowed)
				(pads allowed)
				(copperpour not_allowed)
				(footprints allowed)
			)
			(placement
				(enabled no)
				(sheetname "")
			)
			(fill
				(thermal_gap 0.5)
				(thermal_bridge_width 0.5)
				(island_removal_mode 0)
			)
			(polygon
				(pts
					(xy 336.394806 -60.622434) (xy 335.886806 -60.622434) (xy 335.886806 -61.003434) (xy 336.394806 -61.003434)
				)
			)
		)
	)
	(footprint ""
		(layer "B.Cu")
		(at 481.0379 -147.977098)
		(property "Reference" "Q6W2"
			(at 0.229362 -1.2065 0)
			(unlocked yes)
			(layer "B.SilkS")
			(effects
				(font
					(size 0.4064 0.254)
					(thickness 0.1524)
				)
				(justify left mirror)
			)
		)
		(property "Value" ""
			(at 0 0 0)
			(layer "B.Fab")
			(effects
				(font
					(size 1.27 1.27)
				)
				(justify mirror)
			)
		)
		(duplicate_pad_numbers_are_jumpers no)
		(fp_line
			(start -1.778 -0.5715)
			(end -1.778 0.3175)
			(stroke
				(width 0.1524)
				(type default)
			)
			(layer "B.SilkS")
		)
		(fp_line
			(start -1.778 2.4765)
			(end -1.778 1.5875)
			(stroke
				(width 0.1524)
				(type default)
			)
			(layer "B.SilkS")
		)
		(fp_line
			(start -0.9525 -0.5715)
			(end -1.778 -0.5715)
			(stroke
				(width 0.1524)
				(type default)
			)
			(layer "B.SilkS")
		)
		(fp_line
			(start -0.9525 2.4765)
			(end -1.778 2.4765)
			(stroke
				(width 0.1524)
				(type default)
			)
			(layer "B.SilkS")
		)
		(fp_line
			(start -0.381 0.635)
			(end -0.381 1.27)
			(stroke
				(width 0.1524)
				(type default)
			)
			(layer "B.SilkS")
		)
		(fp_circle
			(center 0.758952 -0.88773)
			(end 0.885952 -0.88773)
			(stroke
				(width 0.254)
				(type default)
			)
			(fill no)
			(layer "B.SilkS")
		)
		(fp_poly
			(pts
				(xy -1.778 2.4765) (xy -0.381 2.4765) (xy -0.381 -0.5715) (xy -1.778 -0.5715)
			)
			(stroke
				(width 0)
				(type default)
			)
			(fill no)
			(layer "B.CrtYd")
		)
		(fp_line
			(start -1.778 -0.5715)
			(end -0.381 -0.5715)
			(stroke
				(width 0.1)
				(type default)
			)
			(layer "B.Fab")
		)
		(fp_line
			(start -1.778 2.4765)
			(end -1.778 -0.5715)
			(stroke
				(width 0.1)
				(type default)
			)
			(layer "B.Fab")
		)
		(fp_line
			(start -0.381 -0.5715)
			(end -0.381 2.4765)
			(stroke
				(width 0.1)
				(type default)
			)
			(layer "B.Fab")
		)
		(fp_line
			(start -0.381 2.4765)
			(end -1.778 2.4765)
			(stroke
				(width 0.1)
				(type default)
			)
			(layer "B.Fab")
		)
		(fp_circle
			(center 0.9525 -0.9271)
			(end 1.0795 -0.9271)
			(stroke
				(width 0.254)
				(type default)
			)
			(fill no)
			(layer "B.Fab")
		)
		(pad "1" smd rect
			(at 0 0 180)
			(size 1.143 0.508)
			(layers "B.Cu" "B.Mask" "B.Paste")
			(net "FM_UART_SEL_N")
		)
		(pad "2" smd rect
			(at 0 1.905 180)
			(size 1.143 0.508)
			(layers "B.Cu" "B.Mask" "B.Paste")
			(net "GND")
		)
		(pad "3" smd rect
			(at -2.159 0.9525 180)
			(size 1.143 0.508)
			(layers "B.Cu" "B.Mask" "B.Paste")
			(net "FM_SOL_UART_CH_SEL")
		)
	)
	(footprint ""
		(layer "B.Cu")
		(at 447.04 -19.939 -90)
		(property "Reference" "Q9W4"
			(at 0 0 90)
			(layer "B.SilkS")
			(hide yes)
			(effects
				(font
					(size 1.27 1.27)
				)
				(justify mirror)
			)
		)
		(property "Value" "*"
			(at 2.3368 -8.8011 270)
			(unlocked yes)
			(layer "B.Fab")
			(hide yes)
			(effects
				(font
					(size 1.27 1.016)
					(thickness 0.1524)
				)
				(justify mirror)
			)
		)
		(property "Device Type" "LMV331IDCKRG4-GP_DISCRET-G-LMVA"
			(at 2.3114 -10.5283 270)
			(unlocked yes)
			(layer "B.Fab")
			(hide yes)
			(effects
				(font
					(size 1.27 1.016)
					(thickness 0.1524)
				)
				(justify mirror)
			)
		)
		(duplicate_pad_numbers_are_jumpers no)
		(fp_line
			(start -1.27 1.7018)
			(end 1.27 1.7018)
			(stroke
				(width 0.1524)
				(type default)
			)
			(layer "B.SilkS")
		)
		(fp_line
			(start 1.27 1.7018)
			(end 1.27 -1.7018)
			(stroke
				(width 0.1524)
				(type default)
			)
			(layer "B.SilkS")
		)
		(fp_line
			(start -1.27 -1.7018)
			(end -1.27 1.7018)
			(stroke
				(width 0.1524)
				(type default)
			)
			(layer "B.SilkS")
		)
		(fp_line
			(start 1.27 -1.7018)
			(end -1.27 -1.7018)
			(stroke
				(width 0.1524)
				(type default)
			)
			(layer "B.SilkS")
		)
		(fp_line
			(start -1.3843 -1.8034)
			(end -1.3843 -1.1176)
			(stroke
				(width 0.3302)
				(type default)
			)
			(layer "B.SilkS")
		)
		(fp_line
			(start -0.6604 -1.8034)
			(end -1.3843 -1.8034)
			(stroke
				(width 0.3302)
				(type default)
			)
			(layer "B.SilkS")
		)
		(fp_rect
			(start 1.524 1.9558)
			(end -1.524 -1.9558)
			(stroke
				(width 0)
				(type default)
			)
			(fill no)
			(layer "B.CrtYd")
		)
		(fp_poly
			(pts
				(xy 1.524 -1.9558) (xy -1.524 -1.9558) (xy -1.524 1.9558) (xy 1.524 1.9558)
			)
			(stroke
				(width 0)
				(type default)
			)
			(fill no)
			(layer "B.Fab")
		)
		(pad "1" smd rect
			(at -0.65024 -0.8255 90)
			(size 0.4064 1.2192)
			(layers "B.Cu" "B.Mask" "B.Paste")
			(net "FM_TPM_PRES_RST_N")
		)
		(pad "2" smd rect
			(at 0 -0.8255 90)
			(size 0.4064 1.2192)
			(layers "B.Cu" "B.Mask" "B.Paste")
			(net "GND")
		)
		(pad "3" smd rect
			(at 0.65024 -0.8255 90)
			(size 0.4064 1.2192)
			(layers "B.Cu" "B.Mask" "B.Paste")
			(net "VREF_2V2")
		)
		(pad "4" smd rect
			(at 0.65024 0.8255 90)
			(size 0.4064 1.2192)
			(layers "B.Cu" "B.Mask" "B.Paste")
			(net "FM_TPM_PRES_N")
		)
		(pad "5" smd rect
			(at -0.65024 0.8255 90)
			(size 0.4064 1.2192)
			(layers "B.Cu" "B.Mask" "B.Paste")
			(net "P5V_STBY")
		)
	)
	(footprint ""
		(layer "B.Cu")
		(at 376.418348 -47.007018 180)
		(property "Reference" "U7E3"
			(at -2.286 -1.281684 0)
			(unlocked yes)
			(layer "B.SilkS")
			(effects
				(font
					(size 0.7874 0.5842)
					(thickness 0.1524)
				)
				(justify left mirror)
			)
		)
		(property "Value" ""
			(at 0 0 0)
			(layer "B.Fab")
			(effects
				(font
					(size 1.27 1.27)
				)
				(justify mirror)
			)
		)
		(duplicate_pad_numbers_are_jumpers no)
		(fp_circle
			(center 0.402844 -0.6604)
			(end 0.275844 -0.6604)
			(stroke
				(width 0.254)
				(type default)
			)
			(fill no)
			(layer "B.SilkS")
		)
		(fp_poly
			(pts
				(xy -0.21463 -0.450088) (xy -1.56337 -0.450088) (xy -1.56337 1.75006) (xy -0.21463 1.75006)
			)
			(stroke
				(width 0)
				(type default)
			)
			(fill no)
			(layer "B.CrtYd")
		)
		(fp_line
			(start -0.21463 1.75006)
			(end -0.21463 -0.450088)
			(stroke
				(width 0.1)
				(type default)
			)
			(layer "B.Fab")
		)
		(fp_line
			(start -0.21463 -0.450088)
			(end -1.56337 -0.450088)
			(stroke
				(width 0.1)
				(type default)
			)
			(layer "B.Fab")
		)
		(fp_line
			(start -1.56337 1.75006)
			(end -0.21463 1.75006)
			(stroke
				(width 0.1)
				(type default)
			)
			(layer "B.Fab")
		)
		(fp_line
			(start -1.56337 -0.450088)
			(end -1.56337 1.75006)
			(stroke
				(width 0.1)
				(type default)
			)
			(layer "B.Fab")
		)
		(fp_circle
			(center 0.4699 -0.8382)
			(end 0.3429 -0.8382)
			(stroke
				(width 0.254)
				(type default)
			)
			(fill no)
			(layer "B.Fab")
		)
		(pad "1" smd rect
			(at 0 0)
			(size 1.016 0.381)
			(layers "B.Cu" "B.Mask" "B.Paste")
			(net "FM_PVCCIN_CPU1_PWR_IN_ALERT_N")
		)
		(pad "2" smd rect
			(at 0 0.649986)
			(size 1.016 0.381)
			(layers "B.Cu" "B.Mask" "B.Paste")
			(net "IRQ_PVCCIN_CPU1_VRHOT_LVC3_N")
		)
		(pad "3" smd rect
			(at 0 1.299972)
			(size 1.016 0.381)
			(layers "B.Cu" "B.Mask" "B.Paste")
			(net "GND")
		)
		(pad "4" smd rect
			(at -1.778 1.299972)
			(size 1.016 0.381)
			(layers "B.Cu" "B.Mask" "B.Paste")
			(net "IRQ_CPU1_PROCHOT_G_N")
		)
		(pad "5" smd rect
			(at -1.778 0)
			(size 1.016 0.381)
			(layers "B.Cu" "B.Mask" "B.Paste")
			(net "P3V3_STBY")
		)
	)
)
